# BASEBOARD_FAB2 (Tioga Pass) — schematic netlist excerpt (pin names and nets, part order shuffled) for the footprints in the layout excerpt that follows; sources: Cadence DE-HDL packaged netlist, KiCad conversion of Wiwynn_Tioga_Pass_MB.brd

R25W90  RES  22.1 1.0% CHIP  pkg 0402  page 147 : A = RMII_BMC_PCH_SPRNGVLLE_TXD1_R ; B = RMII_BMC_PCH_SPRNGVLLE_TXD1
R3D20  RES  49.9 1% CHIP  pkg 0402  page 96 : A = PVCCIO_CPU1 ; B = RST_CPU1_G_N
R2N29  RES  1.5K 1% CHIP  pkg 0402  page 133 : A = P3V3_STBY ; B = FM_CPU1_RC_ERROR_N

(kicad_pcb
	(version 20260206)
	(generator "pcbnew")
	(generator_version "10.0")
	(general
		(thickness 1.6)
		(legacy_teardrops no)
	)
	(paper "A4")
	(title_block
		(title "Wiwynn_Tioga_Pass_MB.brd")
		(comment 1 "Tioga Pass / footprints 127-129 of 4770")
	)
	(layers
		(0 "F.Cu" signal "TOP")
		(4 "In1.Cu" signal "L2GND")
		(6 "In2.Cu" signal "L3")
		(8 "In3.Cu" signal "L4GND")
		(10 "In4.Cu" signal "L5")
		(12 "In5.Cu" signal "L6GND")
		(14 "In6.Cu" signal "L7VCC")
		(16 "In7.Cu" signal "L8VCC")
		(18 "In8.Cu" signal "L9GND")
		(20 "In9.Cu" signal "L10")
		(22 "In10.Cu" signal "L11GND")
		(24 "In11.Cu" signal "L12")
		(26 "In12.Cu" signal "L13GND")
		(2 "B.Cu" signal "BOTTOM")
		(9 "F.Adhes" user "F.Adhesive")
		(11 "B.Adhes" user "B.Adhesive")
		(13 "F.Paste" user "Package Geometry/Pastemask Top")
		(15 "B.Paste" user "Package Geometry/Pastemask Bottom")
		(5 "F.SilkS" user "Ref Des/Silkscreen Top")
		(7 "B.SilkS" user "Ref Des/Silkscreen Bottom")
		(1 "F.Mask" user "Board Geometry/Soldermask Top")
		(3 "B.Mask" user "Board Geometry/Soldermask Bottom")
		(17 "Dwgs.User" user "User.Drawings")
		(19 "Cmts.User" user "User.Comments")
		(21 "Eco1.User" user "User.Eco1")
		(23 "Eco2.User" user "User.Eco2")
		(25 "Edge.Cuts" user "Board Geometry/Outline")
		(27 "Margin" user)
		(31 "F.CrtYd" user "Package Geometry/Place Bound Top")
		(29 "B.CrtYd" user "Package Geometry/Place Bound Bottom")
		(35 "F.Fab" user "Ref Des/Assembly Top")
		(33 "B.Fab" user "Ref Des/Assembly Bottom")
	)
	(footprint ""
		(layer "F.Cu")
		(at 162.38728 -68.8467 180)
		(property "Reference" "R3D20"
			(at 0 0 180)
			(layer "F.SilkS")
			(hide yes)
			(effects
				(font
					(size 1.27 1.27)
				)
			)
		)
		(property "Value" ""
			(at 0 0 180)
			(layer "F.Fab")
			(effects
				(font
					(size 1.27 1.27)
				)
			)
		)
		(duplicate_pad_numbers_are_jumpers no)
		(fp_poly
			(pts
				(xy -0.2794 -0.1016) (xy 0.2794 -0.1016) (xy 0.2794 0.9906) (xy -0.2794 0.9906)
			)
			(stroke
				(width 0)
				(type default)
			)
			(fill no)
			(layer "F.CrtYd")
		)
		(fp_line
			(start 0.2794 0.9906)
			(end 0.2794 -0.1016)
			(stroke
				(width 0.1)
				(type default)
			)
			(layer "F.Fab")
		)
		(fp_line
			(start 0.2794 -0.1016)
			(end -0.2794 -0.1016)
			(stroke
				(width 0.1)
				(type default)
			)
			(layer "F.Fab")
		)
		(fp_line
			(start -0.2794 0.9906)
			(end 0.2794 0.9906)
			(stroke
				(width 0.1)
				(type default)
			)
			(layer "F.Fab")
		)
		(fp_line
			(start -0.2794 -0.1016)
			(end -0.2794 0.9906)
			(stroke
				(width 0.1)
				(type default)
			)
			(layer "F.Fab")
		)
		(pad "1" smd rect
			(at 0 0 180)
			(size 0.508 0.508)
			(layers "F.Cu" "F.Mask" "F.Paste")
			(net "PVCCIO_CPU1")
		)
		(pad "2" smd rect
			(at 0 0.889 180)
			(size 0.508 0.508)
			(layers "F.Cu" "F.Mask" "F.Paste")
			(net "RST_CPU1_G_N")
		)
		(zone
			(layer "F.Cu")
			(hatch none 0.5)
			(connect_pads
				(clearance 0)
			)
			(min_thickness 0.25)
			(keepout
				(tracks not_allowed)
				(vias allowed)
				(pads allowed)
				(copperpour not_allowed)
				(footprints allowed)
			)
			(placement
				(enabled no)
				(sheetname "")
			)
			(fill
				(thermal_gap 0.5)
				(thermal_bridge_width 0.5)
				(island_removal_mode 0)
			)
			(polygon
				(pts
					(xy 162.64128 -69.4817) (xy 162.13328 -69.4817) (xy 162.13328 -69.1007) (xy 162.64128 -69.1007)
				)
			)
		)
		(zone
			(layer "F.Cu")
			(hatch none 0.5)
			(connect_pads
				(clearance 0)
			)
			(min_thickness 0.25)
			(keepout
				(tracks allowed)
				(vias not_allowed)
				(pads allowed)
				(copperpour not_allowed)
				(footprints allowed)
			)
			(placement
				(enabled no)
				(sheetname "")
			)
			(fill
				(thermal_gap 0.5)
				(thermal_bridge_width 0.5)
				(island_removal_mode 0)
			)
			(polygon
				(pts
					(xy 162.64128 -69.1007) (xy 162.13328 -69.1007) (xy 162.13328 -69.4817) (xy 162.64128 -69.4817)
				)
			)
		)
	)
	(footprint ""
		(layer "F.Cu")
		(at 412.5468 -102.489 180)
		(property "Reference" "R2N29"
			(at 0 0 180)
			(layer "F.SilkS")
			(hide yes)
			(effects
				(font
					(size 1.27 1.27)
				)
			)
		)
		(property "Value" ""
			(at 0 0 180)
			(layer "F.Fab")
			(effects
				(font
					(size 1.27 1.27)
				)
			)
		)
		(duplicate_pad_numbers_are_jumpers no)
		(fp_poly
			(pts
				(xy -0.2794 -0.1016) (xy 0.2794 -0.1016) (xy 0.2794 0.9906) (xy -0.2794 0.9906)
			)
			(stroke
				(width 0)
				(type default)
			)
			(fill no)
			(layer "F.CrtYd")
		)
		(fp_line
			(start 0.2794 0.9906)
			(end 0.2794 -0.1016)
			(stroke
				(width 0.1)
				(type default)
			)
			(layer "F.Fab")
		)
		(fp_line
			(start 0.2794 -0.1016)
			(end -0.2794 -0.1016)
			(stroke
				(width 0.1)
				(type default)
			)
			(layer "F.Fab")
		)
		(fp_line
			(start -0.2794 0.9906)
			(end 0.2794 0.9906)
			(stroke
				(width 0.1)
				(type default)
			)
			(layer "F.Fab")
		)
		(fp_line
			(start -0.2794 -0.1016)
			(end -0.2794 0.9906)
			(stroke
				(width 0.1)
				(type default)
			)
			(layer "F.Fab")
		)
		(pad "1" smd rect
			(at 0 0 180)
			(size 0.508 0.508)
			(layers "F.Cu" "F.Mask" "F.Paste")
			(net "P3V3_STBY")
		)
		(pad "2" smd rect
			(at 0 0.889 180)
			(size 0.508 0.508)
			(layers "F.Cu" "F.Mask" "F.Paste")
			(net "FM_CPU1_RC_ERROR_N")
		)
		(zone
			(layer "F.Cu")
			(hatch none 0.5)
			(connect_pads
				(clearance 0)
			)
			(min_thickness 0.25)
			(keepout
				(tracks not_allowed)
				(vias allowed)
				(pads allowed)
				(copperpour not_allowed)
				(footprints allowed)
			)
			(placement
				(enabled no)
				(sheetname "")
			)
			(fill
				(thermal_gap 0.5)
				(thermal_bridge_width 0.5)
				(island_removal_mode 0)
			)
			(polygon
				(pts
					(xy 412.8008 -103.124) (xy 412.2928 -103.124) (xy 412.2928 -102.743) (xy 412.8008 -102.743)
				)
			)
		)
		(zone
			(layer "F.Cu")
			(hatch none 0.5)
			(connect_pads
				(clearance 0)
			)
			(min_thickness 0.25)
			(keepout
				(tracks allowed)
				(vias not_allowed)
				(pads allowed)
				(copperpour not_allowed)
				(footprints allowed)
			)
			(placement
				(enabled no)
				(sheetname "")
			)
			(fill
				(thermal_gap 0.5)
				(thermal_bridge_width 0.5)
				(island_removal_mode 0)
			)
			(polygon
				(pts
					(xy 412.8008 -102.743) (xy 412.2928 -102.743) (xy 412.2928 -103.124) (xy 412.8008 -103.124)
				)
			)
		)
	)
	(footprint ""
		(layer "F.Cu")
		(at 402.971 -22.987)
		(property "Reference" "R25W90"
			(at -0.8382 -0.67818 0)
			(unlocked yes)
			(layer "F.SilkS")
			(effects
				(font
					(size 0.4064 0.254)
					(thickness 0.1524)
				)
				(justify left)
			)
		)
		(property "Value" ""
			(at 0 0 0)
			(layer "F.Fab")
			(effects
				(font
					(size 1.27 1.27)
				)
			)
		)
		(duplicate_pad_numbers_are_jumpers no)
		(fp_poly
			(pts
				(xy -0.2794 -0.1016) (xy 0.2794 -0.1016) (xy 0.2794 0.9906) (xy -0.2794 0.9906)
			)
			(stroke
				(width 0)
				(type default)
			)
			(fill no)
			(layer "F.CrtYd")
		)
		(fp_line
			(start -0.2794 -0.1016)
			(end -0.2794 0.9906)
			(stroke
				(width 0.1)
				(type default)
			)
			(layer "F.Fab")
		)
		(fp_line
			(start -0.2794 0.9906)
			(end 0.2794 0.9906)
			(stroke
				(width 0.1)
				(type default)
			)
			(layer "F.Fab")
		)
		(fp_line
			(start 0.2794 -0.1016)
			(end -0.2794 -0.1016)
			(stroke
				(width 0.1)
				(type default)
			)
			(layer "F.Fab")
		)
		(fp_line
			(start 0.2794 0.9906)
			(end 0.2794 -0.1016)
			(stroke
				(width 0.1)
				(type default)
			)
			(layer "F.Fab")
		)
		(pad "1" smd rect
			(at 0 0)
			(size 0.508 0.508)
			(layers "F.Cu" "F.Mask" "F.Paste")
			(net "RMII_BMC_PCH_SPRNGVLLE_TXD1_R")
		)
		(pad "2" smd rect
			(at 0 0.889)
			(size 0.508 0.508)
			(layers "F.Cu" "F.Mask" "F.Paste")
			(net "RMII_BMC_PCH_SPRNGVLLE_TXD1")
		)
		(zone
			(layer "F.Cu")
			(hatch none 0.5)
			(connect_pads
				(clearance 0)
			)
			(min_thickness 0.25)
			(keepout
				(tracks allowed)
				(vias not_allowed)
				(pads allowed)
				(copperpour not_allowed)
				(footprints allowed)
			)
			(placement
				(enabled no)
				(sheetname "")
			)
			(fill
				(thermal_gap 0.5)
				(thermal_bridge_width 0.5)
				(island_removal_mode 0)
			)
			(polygon
				(pts
					(xy 402.717 -22.733) (xy 403.225 -22.733) (xy 403.225 -22.352) (xy 402.717 -22.352)
				)
			)
		)
		(zone
			(layer "F.Cu")
			(hatch none 0.5)
			(connect_pads
				(clearance 0)
			)
			(min_thickness 0.25)
			(keepout
				(tracks not_allowed)
				(vias allowed)
				(pads allowed)
				(copperpour not_allowed)
				(footprints allowed)
			)
			(placement
				(enabled no)
				(sheetname "")
			)
			(fill
				(thermal_gap 0.5)
				(thermal_bridge_width 0.5)
				(island_removal_mode 0)
			)
			(polygon
				(pts
					(xy 402.717 -22.352) (xy 403.225 -22.352) (xy 403.225 -22.733) (xy 402.717 -22.733)
				)
			)
		)
	)
)
